(kicad_pcb
	(version 20260206)
	(generator "pcbnew")
	(generator_version "10.0")
	(general
		(thickness 1.6)
		(legacy_teardrops no)
	)
	(paper "A4")
	(title_block
		(title "01162023_DA0F0TEBIF0_F0T_Expander_BD_F_brd_V02_OCP.brd")
		(comment 1 "Grand Teton / footprints 2805-2812 of 9728")
	)
	(layers
		(0 "F.Cu" signal "TOP")
		(4 "In1.Cu" signal "GND")
		(6 "In2.Cu" signal "VCC")
		(8 "In3.Cu" signal "VCC1")
		(10 "In4.Cu" signal "GND1")
		(12 "In5.Cu" signal "IN1")
		(14 "In6.Cu" signal "GND2")
		(16 "In7.Cu" signal "IN2")
		(18 "In8.Cu" signal "GND3")
		(20 "In9.Cu" signal "IN3")
		(22 "In10.Cu" signal "GND4")
		(24 "In11.Cu" signal "IN4")
		(26 "In12.Cu" signal "GND5")
		(28 "In13.Cu" signal "IN5")
		(30 "In14.Cu" signal "GND6")
		(32 "In15.Cu" signal "IN6")
		(34 "In16.Cu" signal "GND7")
		(2 "B.Cu" signal "BOTTOM")
		(9 "F.Adhes" user "F.Adhesive")
		(11 "B.Adhes" user "B.Adhesive")
		(13 "F.Paste" user "Package Geometry/Pastemask Top")
		(15 "B.Paste" user "Package Geometry/Pastemask Bottom")
		(5 "F.SilkS" user "Ref Des/Silkscreen Top")
		(7 "B.SilkS" user "Ref Des/Silkscreen Bottom")
		(1 "F.Mask" user "Board Geometry/Soldermask Top")
		(3 "B.Mask" user "Board Geometry/Soldermask Bottom")
		(17 "Dwgs.User" user "User.Drawings")
		(19 "Cmts.User" user "User.Comments")
		(21 "Eco1.User" user "User.Eco1")
		(23 "Eco2.User" user "User.Eco2")
		(25 "Edge.Cuts" user "Board Geometry/Outline")
		(27 "Margin" user)
		(31 "F.CrtYd" user "Package Geometry/Place Bound Top")
		(29 "B.CrtYd" user "Package Geometry/Place Bound Bottom")
		(35 "F.Fab" user "Ref Des/Assembly Top")
		(33 "B.Fab" user "Ref Des/Assembly Bottom")
	)
	(footprint ""
		(layer "F.Cu")
		(at 19.738594 -44.341542 90)
		(property "Reference" "C203"
			(at 0 0 90)
			(layer "F.SilkS")
			(hide yes)
			(effects
				(font
					(size 1.27 1.27)
				)
			)
		)
		(property "Value" ""
			(at 0 0 90)
			(layer "F.Fab")
			(effects
				(font
					(size 1.27 1.27)
				)
			)
		)
		(duplicate_pad_numbers_are_jumpers no)
		(fp_line
			(start 0.7874 -0.4064)
			(end 0.7874 0.4064)
			(stroke
				(width 0.1524)
				(type default)
			)
			(layer "F.SilkS")
		)
		(fp_line
			(start -0.7874 -0.4064)
			(end 0.7874 -0.4064)
			(stroke
				(width 0.1524)
				(type default)
			)
			(layer "F.SilkS")
		)
		(fp_line
			(start 0.7874 0.4064)
			(end -0.7874 0.4064)
			(stroke
				(width 0.1524)
				(type default)
			)
			(layer "F.SilkS")
		)
		(fp_line
			(start -0.7874 0.4064)
			(end -0.7874 -0.4064)
			(stroke
				(width 0.1524)
				(type default)
			)
			(layer "F.SilkS")
		)
		(fp_line
			(start -0.12065 -0.305054)
			(end -0.12065 -0.2794)
			(stroke
				(width 0.1)
				(type default)
			)
			(layer "F.Fab")
		)
		(fp_line
			(start -0.67945 -0.305054)
			(end -0.12065 -0.305054)
			(stroke
				(width 0.1)
				(type default)
			)
			(layer "F.Fab")
		)
		(fp_line
			(start 0.67945 -0.3048)
			(end 0.67945 0.3048)
			(stroke
				(width 0.1)
				(type default)
			)
			(layer "F.Fab")
		)
		(fp_line
			(start 0.12065 -0.3048)
			(end 0.67945 -0.3048)
			(stroke
				(width 0.1)
				(type default)
			)
			(layer "F.Fab")
		)
		(fp_line
			(start 0.12065 -0.2794)
			(end 0.12065 -0.3048)
			(stroke
				(width 0.1)
				(type default)
			)
			(layer "F.Fab")
		)
		(fp_line
			(start -0.12065 -0.2794)
			(end 0.12065 -0.2794)
			(stroke
				(width 0.1)
				(type default)
			)
			(layer "F.Fab")
		)
		(fp_line
			(start 0.120396 0.2794)
			(end -0.12065 0.2794)
			(stroke
				(width 0.1)
				(type default)
			)
			(layer "F.Fab")
		)
		(fp_line
			(start -0.12065 0.2794)
			(end -0.12065 0.3048)
			(stroke
				(width 0.1)
				(type default)
			)
			(layer "F.Fab")
		)
		(fp_line
			(start 0.67945 0.3048)
			(end 0.120396 0.3048)
			(stroke
				(width 0.1)
				(type default)
			)
			(layer "F.Fab")
		)
		(fp_line
			(start 0.120396 0.3048)
			(end 0.120396 0.2794)
			(stroke
				(width 0.1)
				(type default)
			)
			(layer "F.Fab")
		)
		(fp_line
			(start -0.12065 0.3048)
			(end -0.67945 0.3048)
			(stroke
				(width 0.1)
				(type default)
			)
			(layer "F.Fab")
		)
		(fp_line
			(start -0.67945 0.3048)
			(end -0.67945 -0.305054)
			(stroke
				(width 0.1)
				(type default)
			)
			(layer "F.Fab")
		)
		(pad "1" smd circle
			(at -0.40005 0 90)
			(size 0 0)
			(layers "F.Cu" "F.Mask" "F.Paste")
			(net "P12V_SSD0_VIN_P")
		)
		(pad "2" smd circle
			(at 0.40005 0 90)
			(size 0 0)
			(layers "F.Cu" "F.Mask" "F.Paste")
			(net "P12V_SSD0_VIN_N")
		)
	)
	(footprint ""
		(layer "F.Cu")
		(at 91.044522 -298.624244 -90)
		(property "Reference" "R4013"
			(at 0 0 270)
			(layer "F.SilkS")
			(hide yes)
			(effects
				(font
					(size 1.27 1.27)
				)
			)
		)
		(property "Value" ""
			(at 0 0 270)
			(layer "F.Fab")
			(effects
				(font
					(size 1.27 1.27)
				)
			)
		)
		(duplicate_pad_numbers_are_jumpers no)
		(fp_line
			(start -0.7874 0.4064)
			(end -0.7874 -0.4064)
			(stroke
				(width 0.1524)
				(type default)
			)
			(layer "F.SilkS")
		)
		(fp_line
			(start 0.7874 0.4064)
			(end -0.7874 0.4064)
			(stroke
				(width 0.1524)
				(type default)
			)
			(layer "F.SilkS")
		)
		(fp_line
			(start -0.7874 -0.4064)
			(end 0.7874 -0.4064)
			(stroke
				(width 0.1524)
				(type default)
			)
			(layer "F.SilkS")
		)
		(fp_line
			(start 0.7874 -0.4064)
			(end 0.7874 0.4064)
			(stroke
				(width 0.1524)
				(type default)
			)
			(layer "F.SilkS")
		)
		(fp_line
			(start -0.67945 0.3048)
			(end -0.67945 -0.305054)
			(stroke
				(width 0.1)
				(type default)
			)
			(layer "F.Fab")
		)
		(fp_line
			(start -0.12065 0.3048)
			(end -0.67945 0.3048)
			(stroke
				(width 0.1)
				(type default)
			)
			(layer "F.Fab")
		)
		(fp_line
			(start 0.120396 0.3048)
			(end 0.120396 0.2794)
			(stroke
				(width 0.1)
				(type default)
			)
			(layer "F.Fab")
		)
		(fp_line
			(start 0.67945 0.3048)
			(end 0.120396 0.3048)
			(stroke
				(width 0.1)
				(type default)
			)
			(layer "F.Fab")
		)
		(fp_line
			(start -0.12065 0.2794)
			(end -0.12065 0.3048)
			(stroke
				(width 0.1)
				(type default)
			)
			(layer "F.Fab")
		)
		(fp_line
			(start 0.120396 0.2794)
			(end -0.12065 0.2794)
			(stroke
				(width 0.1)
				(type default)
			)
			(layer "F.Fab")
		)
		(fp_line
			(start -0.12065 -0.2794)
			(end 0.12065 -0.2794)
			(stroke
				(width 0.1)
				(type default)
			)
			(layer "F.Fab")
		)
		(fp_line
			(start 0.12065 -0.2794)
			(end 0.12065 -0.3048)
			(stroke
				(width 0.1)
				(type default)
			)
			(layer "F.Fab")
		)
		(fp_line
			(start 0.12065 -0.3048)
			(end 0.67945 -0.3048)
			(stroke
				(width 0.1)
				(type default)
			)
			(layer "F.Fab")
		)
		(fp_line
			(start 0.67945 -0.3048)
			(end 0.67945 0.3048)
			(stroke
				(width 0.1)
				(type default)
			)
			(layer "F.Fab")
		)
		(fp_line
			(start -0.67945 -0.305054)
			(end -0.12065 -0.305054)
			(stroke
				(width 0.1)
				(type default)
			)
			(layer "F.Fab")
		)
		(fp_line
			(start -0.12065 -0.305054)
			(end -0.12065 -0.2794)
			(stroke
				(width 0.1)
				(type default)
			)
			(layer "F.Fab")
		)
		(pad "1" smd circle
			(at -0.40005 0 270)
			(size 0 0)
			(layers "F.Cu" "F.Mask" "F.Paste")
			(net "P1V8_PEX")
		)
		(pad "2" smd circle
			(at 0.40005 0 270)
			(size 0 0)
			(layers "F.Cu" "F.Mask" "F.Paste")
			(net "I2C_PEX0_HOST_R_SCL")
		)
	)
	(footprint ""
		(layer "F.Cu")
		(at 16.785336 -276.264624)
		(property "Reference" "R768"
			(at 0 0 0)
			(layer "F.SilkS")
			(hide yes)
			(effects
				(font
					(size 1.27 1.27)
				)
			)
		)
		(property "Value" ""
			(at 0 0 0)
			(layer "F.Fab")
			(effects
				(font
					(size 1.27 1.27)
				)
			)
		)
		(duplicate_pad_numbers_are_jumpers no)
		(fp_line
			(start -0.7874 -0.4064)
			(end 0.7874 -0.4064)
			(stroke
				(width 0.1524)
				(type default)
			)
			(layer "F.SilkS")
		)
		(fp_line
			(start -0.7874 0.4064)
			(end -0.7874 -0.4064)
			(stroke
				(width 0.1524)
				(type default)
			)
			(layer "F.SilkS")
		)
		(fp_line
			(start 0.7874 -0.4064)
			(end 0.7874 0.4064)
			(stroke
				(width 0.1524)
				(type default)
			)
			(layer "F.SilkS")
		)
		(fp_line
			(start 0.7874 0.4064)
			(end -0.7874 0.4064)
			(stroke
				(width 0.1524)
				(type default)
			)
			(layer "F.SilkS")
		)
		(fp_line
			(start -0.67945 -0.305054)
			(end -0.12065 -0.305054)
			(stroke
				(width 0.1)
				(type default)
			)
			(layer "F.Fab")
		)
		(fp_line
			(start -0.67945 0.3048)
			(end -0.67945 -0.305054)
			(stroke
				(width 0.1)
				(type default)
			)
			(layer "F.Fab")
		)
		(fp_line
			(start -0.12065 -0.305054)
			(end -0.12065 -0.2794)
			(stroke
				(width 0.1)
				(type default)
			)
			(layer "F.Fab")
		)
		(fp_line
			(start -0.12065 -0.2794)
			(end 0.12065 -0.2794)
			(stroke
				(width 0.1)
				(type default)
			)
			(layer "F.Fab")
		)
		(fp_line
			(start -0.12065 0.2794)
			(end -0.12065 0.3048)
			(stroke
				(width 0.1)
				(type default)
			)
			(layer "F.Fab")
		)
		(fp_line
			(start -0.12065 0.3048)
			(end -0.67945 0.3048)
			(stroke
				(width 0.1)
				(type default)
			)
			(layer "F.Fab")
		)
		(fp_line
			(start 0.120396 0.2794)
			(end -0.12065 0.2794)
			(stroke
				(width 0.1)
				(type default)
			)
			(layer "F.Fab")
		)
		(fp_line
			(start 0.120396 0.3048)
			(end 0.120396 0.2794)
			(stroke
				(width 0.1)
				(type default)
			)
			(layer "F.Fab")
		)
		(fp_line
			(start 0.12065 -0.3048)
			(end 0.67945 -0.3048)
			(stroke
				(width 0.1)
				(type default)
			)
			(layer "F.Fab")
		)
		(fp_line
			(start 0.12065 -0.2794)
			(end 0.12065 -0.3048)
			(stroke
				(width 0.1)
				(type default)
			)
			(layer "F.Fab")
		)
		(fp_line
			(start 0.67945 -0.3048)
			(end 0.67945 0.3048)
			(stroke
				(width 0.1)
				(type default)
			)
			(layer "F.Fab")
		)
		(fp_line
			(start 0.67945 0.3048)
			(end 0.120396 0.3048)
			(stroke
				(width 0.1)
				(type default)
			)
			(layer "F.Fab")
		)
		(pad "1" smd circle
			(at -0.40005 0)
			(size 0 0)
			(layers "F.Cu" "F.Mask" "F.Paste")
			(net "P3V3_AUX")
		)
		(pad "2" smd circle
			(at 0.40005 0)
			(size 0 0)
			(layers "F.Cu" "F.Mask" "F.Paste")
			(net "PEX_ADC_ALERT_N")
		)
	)
	(footprint ""
		(layer "F.Cu")
		(at 430.961546 -144.396714 180)
		(property "Reference" "C647"
			(at 0 0 180)
			(layer "F.SilkS")
			(hide yes)
			(effects
				(font
					(size 1.27 1.27)
				)
			)
		)
		(property "Value" ""
			(at 0 0 180)
			(layer "F.Fab")
			(effects
				(font
					(size 1.27 1.27)
				)
			)
		)
		(duplicate_pad_numbers_are_jumpers no)
		(fp_line
			(start 0.299974 0.150114)
			(end -0.299974 0.150114)
			(stroke
				(width 0.1)
				(type default)
			)
			(layer "F.Fab")
		)
		(fp_line
			(start 0.299974 -0.150114)
			(end 0.299974 0.150114)
			(stroke
				(width 0.1)
				(type default)
			)
			(layer "F.Fab")
		)
		(fp_line
			(start -0.299974 0.150114)
			(end -0.299974 -0.150114)
			(stroke
				(width 0.1)
				(type default)
			)
			(layer "F.Fab")
		)
		(fp_line
			(start -0.299974 -0.150114)
			(end 0.299974 -0.150114)
			(stroke
				(width 0.1)
				(type default)
			)
			(layer "F.Fab")
		)
		(pad "1" smd rect
			(at -0.2667 0 180)
			(size 0.3048 0.381)
			(layers "F.Cu" "F.Mask" "F.Paste")
			(net "P5E_PEX3_STN0_TX_DN<9>")
		)
		(pad "2" smd rect
			(at 0.2667 0 180)
			(size 0.3048 0.381)
			(layers "F.Cu" "F.Mask" "F.Paste")
			(net "P5E_PEX3_STN0_TX_C_DN<9>")
		)
	)
	(footprint ""
		(layer "F.Cu")
		(at 199.49414 -29.507688 -90)
		(property "Reference" "PC933"
			(at 0 0 270)
			(layer "F.SilkS")
			(hide yes)
			(effects
				(font
					(size 1.27 1.27)
				)
			)
		)
		(property "Value" ""
			(at 0 0 270)
			(layer "F.Fab")
			(effects
				(font
					(size 1.27 1.27)
				)
			)
		)
		(duplicate_pad_numbers_are_jumpers no)
		(fp_line
			(start -1.524 0.762)
			(end -1.524 -0.762)
			(stroke
				(width 0.1524)
				(type default)
			)
			(layer "F.SilkS")
		)
		(fp_line
			(start 1.524 0.762)
			(end -1.524 0.762)
			(stroke
				(width 0.1524)
				(type default)
			)
			(layer "F.SilkS")
		)
		(fp_line
			(start -1.524 -0.762)
			(end 1.524 -0.762)
			(stroke
				(width 0.1524)
				(type default)
			)
			(layer "F.SilkS")
		)
		(fp_line
			(start 1.524 -0.762)
			(end 1.524 0.762)
			(stroke
				(width 0.1524)
				(type default)
			)
			(layer "F.SilkS")
		)
		(fp_line
			(start -1.1049 0.724916)
			(end 1.1049 0.724916)
			(stroke
				(width 0.1)
				(type default)
			)
			(layer "F.Fab")
		)
		(fp_line
			(start 1.1049 0.724916)
			(end 1.1049 -0.724916)
			(stroke
				(width 0.1)
				(type default)
			)
			(layer "F.Fab")
		)
		(fp_line
			(start -1.1049 -0.724916)
			(end -1.1049 0.724916)
			(stroke
				(width 0.1)
				(type default)
			)
			(layer "F.Fab")
		)
		(fp_line
			(start 1.1049 -0.724916)
			(end -1.1049 -0.724916)
			(stroke
				(width 0.1)
				(type default)
			)
			(layer "F.Fab")
		)
		(pad "1" smd rect
			(at -0.889 0 90)
			(size 1.016 1.27)
			(layers "F.Cu" "F.Mask" "F.Paste")
			(net "P3V3_SSD7")
		)
		(pad "2" smd rect
			(at 0.889 0 90)
			(size 1.016 1.27)
			(layers "F.Cu" "F.Mask" "F.Paste")
			(net "GND")
		)
	)
	(footprint ""
		(layer "F.Cu")
		(at 236.072172 -32.848042 90)
		(property "Reference" "PC940"
			(at 0 0 90)
			(layer "F.SilkS")
			(hide yes)
			(effects
				(font
					(size 1.27 1.27)
				)
			)
		)
		(property "Value" ""
			(at 0 0 90)
			(layer "F.Fab")
			(effects
				(font
					(size 1.27 1.27)
				)
			)
		)
		(duplicate_pad_numbers_are_jumpers no)
		(fp_line
			(start 0.7874 -0.4064)
			(end 0.7874 0.4064)
			(stroke
				(width 0.1524)
				(type default)
			)
			(layer "F.SilkS")
		)
		(fp_line
			(start -0.7874 -0.4064)
			(end 0.7874 -0.4064)
			(stroke
				(width 0.1524)
				(type default)
			)
			(layer "F.SilkS")
		)
		(fp_line
			(start 0.7874 0.4064)
			(end -0.7874 0.4064)
			(stroke
				(width 0.1524)
				(type default)
			)
			(layer "F.SilkS")
		)
		(fp_line
			(start -0.7874 0.4064)
			(end -0.7874 -0.4064)
			(stroke
				(width 0.1524)
				(type default)
			)
			(layer "F.SilkS")
		)
		(fp_line
			(start -0.12065 -0.305054)
			(end -0.12065 -0.2794)
			(stroke
				(width 0.1)
				(type default)
			)
			(layer "F.Fab")
		)
		(fp_line
			(start -0.67945 -0.305054)
			(end -0.12065 -0.305054)
			(stroke
				(width 0.1)
				(type default)
			)
			(layer "F.Fab")
		)
		(fp_line
			(start 0.67945 -0.3048)
			(end 0.67945 0.3048)
			(stroke
				(width 0.1)
				(type default)
			)
			(layer "F.Fab")
		)
		(fp_line
			(start 0.12065 -0.3048)
			(end 0.67945 -0.3048)
			(stroke
				(width 0.1)
				(type default)
			)
			(layer "F.Fab")
		)
		(fp_line
			(start 0.12065 -0.2794)
			(end 0.12065 -0.3048)
			(stroke
				(width 0.1)
				(type default)
			)
			(layer "F.Fab")
		)
		(fp_line
			(start -0.12065 -0.2794)
			(end 0.12065 -0.2794)
			(stroke
				(width 0.1)
				(type default)
			)
			(layer "F.Fab")
		)
		(fp_line
			(start 0.120396 0.2794)
			(end -0.12065 0.2794)
			(stroke
				(width 0.1)
				(type default)
			)
			(layer "F.Fab")
		)
		(fp_line
			(start -0.12065 0.2794)
			(end -0.12065 0.3048)
			(stroke
				(width 0.1)
				(type default)
			)
			(layer "F.Fab")
		)
		(fp_line
			(start 0.67945 0.3048)
			(end 0.120396 0.3048)
			(stroke
				(width 0.1)
				(type default)
			)
			(layer "F.Fab")
		)
		(fp_line
			(start 0.120396 0.3048)
			(end 0.120396 0.2794)
			(stroke
				(width 0.1)
				(type default)
			)
			(layer "F.Fab")
		)
		(fp_line
			(start -0.12065 0.3048)
			(end -0.67945 0.3048)
			(stroke
				(width 0.1)
				(type default)
			)
			(layer "F.Fab")
		)
		(fp_line
			(start -0.67945 0.3048)
			(end -0.67945 -0.305054)
			(stroke
				(width 0.1)
				(type default)
			)
			(layer "F.Fab")
		)
		(pad "1" smd circle
			(at -0.40005 0 90)
			(size 0 0)
			(layers "F.Cu" "F.Mask" "F.Paste")
			(net "P3V3_SSD8_CO_GATE")
		)
		(pad "2" smd circle
			(at 0.40005 0 90)
			(size 0 0)
			(layers "F.Cu" "F.Mask" "F.Paste")
			(net "GND")
		)
	)
	(footprint ""
		(layer "F.Cu")
		(at 109.403896 -395.746732 -90)
		(property "Reference" "Y8"
			(at -2.314702 0.448818 0)
			(unlocked yes)
			(layer "F.SilkS")
			(effects
				(font
					(size 0.7874 0.5842)
					(thickness 0.1524)
				)
			)
		)
		(property "Value" ""
			(at 0 0 270)
			(layer "F.Fab")
			(effects
				(font
					(size 1.27 1.27)
				)
			)
		)
		(duplicate_pad_numbers_are_jumpers no)
		(fp_line
			(start -1.2446 1.4986)
			(end 1.2446 1.4986)
			(stroke
				(width 0.1524)
				(type default)
			)
			(layer "F.SilkS")
		)
		(fp_line
			(start 1.2446 1.4986)
			(end 1.2446 -1.4986)
			(stroke
				(width 0.1524)
				(type default)
			)
			(layer "F.SilkS")
		)
		(fp_line
			(start -1.2446 -1.4986)
			(end -1.2446 1.4986)
			(stroke
				(width 0.1524)
				(type default)
			)
			(layer "F.SilkS")
		)
		(fp_line
			(start 1.2446 -1.4986)
			(end -1.2446 -1.4986)
			(stroke
				(width 0.1524)
				(type default)
			)
			(layer "F.SilkS")
		)
		(fp_poly
			(pts
				(xy -2.4638 -1.357884) (xy -2.4638 -0.341884) (xy -1.4478 -0.849884)
			)
			(stroke
				(width 0)
				(type default)
			)
			(fill yes)
			(layer "F.SilkS")
		)
		(fp_line
			(start -1.050036 1.299972)
			(end 1.050036 1.299972)
			(stroke
				(width 0.1)
				(type default)
			)
			(layer "F.Fab")
		)
		(fp_line
			(start 1.050036 1.299972)
			(end 1.050036 -1.299972)
			(stroke
				(width 0.1)
				(type default)
			)
			(layer "F.Fab")
		)
		(fp_line
			(start -1.050036 -1.299972)
			(end -1.050036 1.299972)
			(stroke
				(width 0.1)
				(type default)
			)
			(layer "F.Fab")
		)
		(fp_line
			(start 1.050036 -1.299972)
			(end -1.050036 -1.299972)
			(stroke
				(width 0.1)
				(type default)
			)
			(layer "F.Fab")
		)
		(fp_poly
			(pts
				(xy -2.4638 -1.357884) (xy -2.4638 -0.341884) (xy -1.4478 -0.849884)
			)
			(stroke
				(width 0)
				(type default)
			)
			(fill yes)
			(layer "F.Fab")
		)
		(pad "1" smd rect
			(at -0.649986 -0.849884 90)
			(size 0.9144 1.016)
			(layers "F.Cu" "F.Mask" "F.Paste")
			(net "BIC_USB_HUB_XIN")
		)
		(pad "2" smd rect
			(at -0.649986 0.849884 90)
			(size 0.9144 1.016)
			(layers "F.Cu" "F.Mask" "F.Paste")
			(net "GND")
		)
		(pad "3" smd rect
			(at 0.649986 0.849884 90)
			(size 0.9144 1.016)
			(layers "F.Cu" "F.Mask" "F.Paste")
			(net "BIC_USB_HUB_XOUT_R")
		)
		(pad "4" smd rect
			(at 0.649986 -0.849884 90)
			(size 0.9144 1.016)
			(layers "F.Cu" "F.Mask" "F.Paste")
			(net "GND")
		)
	)
	(footprint ""
		(layer "F.Cu")
		(at 141.07033 -262.645652 90)
		(property "Reference" "C3245"
			(at 0 0 90)
			(layer "F.SilkS")
			(hide yes)
			(effects
				(font
					(size 1.27 1.27)
				)
			)
		)
		(property "Value" ""
			(at 0 0 90)
			(layer "F.Fab")
			(effects
				(font
					(size 1.27 1.27)
				)
			)
		)
		(duplicate_pad_numbers_are_jumpers no)
		(fp_line
			(start 0.299974 -0.150114)
			(end 0.299974 0.150114)
			(stroke
				(width 0.1)
				(type default)
			)
			(layer "F.Fab")
		)
		(fp_line
			(start -0.299974 -0.150114)
			(end 0.299974 -0.150114)
			(stroke
				(width 0.1)
				(type default)
			)
			(layer "F.Fab")
		)
		(fp_line
			(start 0.299974 0.150114)
			(end -0.299974 0.150114)
			(stroke
				(width 0.1)
				(type default)
			)
			(layer "F.Fab")
		)
		(fp_line
			(start -0.299974 0.150114)
			(end -0.299974 -0.150114)
			(stroke
				(width 0.1)
				(type default)
			)
			(layer "F.Fab")
		)
		(pad "1" smd rect
			(at -0.2667 0 90)
			(size 0.3048 0.381)
			(layers "F.Cu" "F.Mask" "F.Paste")
			(net "P1V8_VDDA_PEX1")
		)
		(pad "2" smd rect
			(at 0.2667 0 90)
			(size 0.3048 0.381)
			(layers "F.Cu" "F.Mask" "F.Paste")
			(net "GND")
		)
	)
)
